# T6G (Grand Teton) — schematic netlist excerpt (pin names and nets, part order shuffled) for the footprints in the layout excerpt that follows; sources: Cadence DE-HDL packaged netlist, KiCad conversion of 04192023_DAF0TMB3IC0_F0TG_MB_C_brd_V02_OCP.brd

U181  PCA9539RPW  IC  pkg TSSOP24XB  page 245
  INT  = PU_U181_INT
  A1  = TCA9539_0_ADD1
  RESET  = PU_RST_SMB_U181_N
  IO0_0  = RST_USB_HUB_N
  IO0_1  = RST_SWB_BIC_N
  IO0_2  = TP_TCA9539_0_P0_2
  IO0_3  = TP_TCA9539_0_P0_3
  IO0_4  = PRSNT_SWB_ISO_R1_N
  IO0_5  = GPU_PRSNT_N_ISO_R1
  IO0_6  = PRSNT_CABLE_GPU_B3_ISO_R1_N
  IO0_7  = PRSNT_CABLE_SWB_B2_ISO_R_N
  VSS  = GND
  IO1_0  = PRSNT_CABLE_GPU_A2_ISO_R1_N
  IO1_1  = PRSNT_CABLE_SWB_B1_ISO_R_N
  IO1_2  = GPU_BASE_ID0_R
  IO1_3  = GPU_BASE_ID1_R
  IO1_4  = GPU_PEX_STRAP0_R
  IO1_5  = GPU_PEX_STRAP1_R
  IO1_6  = PRSNT_CABLE_GPU_A1_ISO_R1_N
  IO1_7  = PRSNT_CABLE_GPU_A3_ISO_R_N
  A0  = TCA9539_0_ADD0
  SCL  = SMB_IOEXP_3V3AUX_SCL_R1
  SDA  = SMB_IOEXP_3V3AUX_SDA_R1
  VDD  = P3V3_AUX

(kicad_pcb
	(version 20260206)
	(generator "pcbnew")
	(generator_version "10.0")
	(general
		(thickness 1.6)
		(legacy_teardrops no)
	)
	(paper "A4")
	(title_block
		(title "04192023_DAF0TMB3IC0_F0TG_MB_C_brd_V02_OCP.brd")
		(comment 1 "Grand Teton / footprints 1101-1101 of 8354")
	)
	(layers
		(0 "F.Cu" signal "TOP")
		(4 "In1.Cu" signal "GND")
		(6 "In2.Cu" signal "IN1")
		(8 "In3.Cu" signal "GND1")
		(10 "In4.Cu" signal "IN2")
		(12 "In5.Cu" signal "GND2")
		(14 "In6.Cu" signal "IN3")
		(16 "In7.Cu" signal "GND3")
		(18 "In8.Cu" signal "VCC")
		(20 "In9.Cu" signal "VCC1")
		(22 "In10.Cu" signal "GND4")
		(24 "In11.Cu" signal "IN4")
		(26 "In12.Cu" signal "GND5")
		(28 "In13.Cu" signal "IN5")
		(30 "In14.Cu" signal "GND6")
		(32 "In15.Cu" signal "IN6")
		(34 "In16.Cu" signal "GND7")
		(2 "B.Cu" signal "BOTTOM")
		(9 "F.Adhes" user "F.Adhesive")
		(11 "B.Adhes" user "B.Adhesive")
		(13 "F.Paste" user "Package Geometry/Pastemask Top")
		(15 "B.Paste" user "Package Geometry/Pastemask Bottom")
		(5 "F.SilkS" user "Ref Des/Silkscreen Top")
		(7 "B.SilkS" user "Ref Des/Silkscreen Bottom")
		(1 "F.Mask" user "Board Geometry/Soldermask Top")
		(3 "B.Mask" user "Board Geometry/Soldermask Bottom")
		(17 "Dwgs.User" user "User.Drawings")
		(19 "Cmts.User" user "User.Comments")
		(21 "Eco1.User" user "User.Eco1")
		(23 "Eco2.User" user "User.Eco2")
		(25 "Edge.Cuts" user "Board Geometry/Outline")
		(27 "Margin" user)
		(31 "F.CrtYd" user "Package Geometry/Place Bound Top")
		(29 "B.CrtYd" user "Package Geometry/Place Bound Bottom")
		(35 "F.Fab" user "Ref Des/Assembly Top")
		(33 "B.Fab" user "Ref Des/Assembly Bottom")
	)
	(footprint ""
		(layer "F.Cu")
		(at 184.337198 -420.329868 90)
		(property "Reference" "U181"
			(at -0.339344 -7.867396 90)
			(unlocked yes)
			(layer "F.SilkS")
			(effects
				(font
					(size 0.7874 0.5842)
					(thickness 0.1524)
				)
				(justify left)
			)
		)
		(property "Value" ""
			(at 0 0 90)
			(layer "F.Fab")
			(effects
				(font
					(size 1.27 1.27)
				)
			)
		)
		(duplicate_pad_numbers_are_jumpers no)
		(fp_line
			(start 2.097532 -3.949954)
			(end 1.409954 -3.949954)
			(stroke
				(width 0.1524)
				(type default)
			)
			(layer "F.SilkS")
		)
		(fp_line
			(start 1.409954 -3.949954)
			(end 0 -2.54)
			(stroke
				(width 0.1524)
				(type default)
			)
			(layer "F.SilkS")
		)
		(fp_line
			(start -1.409954 -3.949954)
			(end -2.097532 -3.949954)
			(stroke
				(width 0.1524)
				(type default)
			)
			(layer "F.SilkS")
		)
		(fp_line
			(start -2.097532 -3.949954)
			(end -2.097532 3.949954)
			(stroke
				(width 0.1524)
				(type default)
			)
			(layer "F.SilkS")
		)
		(fp_line
			(start 0 -2.54)
			(end -1.409954 -3.949954)
			(stroke
				(width 0.1524)
				(type default)
			)
			(layer "F.SilkS")
		)
		(fp_line
			(start 2.097532 3.949954)
			(end 2.097532 -3.949954)
			(stroke
				(width 0.1524)
				(type default)
			)
			(layer "F.SilkS")
		)
		(fp_line
			(start -2.097532 3.949954)
			(end 2.097532 3.949954)
			(stroke
				(width 0.1524)
				(type default)
			)
			(layer "F.SilkS")
		)
		(fp_poly
			(pts
				(xy -4.509262 -5.070856) (xy -3.67538 -5.650992) (xy -3.512058 -4.527042)
			)
			(stroke
				(width 0)
				(type default)
			)
			(fill yes)
			(layer "F.SilkS")
		)
		(fp_line
			(start 2.249932 -3.949954)
			(end -2.249932 -3.949954)
			(stroke
				(width 0.1)
				(type default)
			)
			(layer "F.Fab")
		)
		(fp_line
			(start -2.249932 -3.949954)
			(end -2.249932 3.949954)
			(stroke
				(width 0.1)
				(type default)
			)
			(layer "F.Fab")
		)
		(fp_line
			(start 2.249932 3.949954)
			(end 2.249932 -3.949954)
			(stroke
				(width 0.1)
				(type default)
			)
			(layer "F.Fab")
		)
		(fp_line
			(start -2.249932 3.949954)
			(end 2.249932 3.949954)
			(stroke
				(width 0.1)
				(type default)
			)
			(layer "F.Fab")
		)
		(fp_poly
			(pts
				(xy -4.7498 -4.182872) (xy -4.7498 -3.166872) (xy -3.7338 -3.674872)
			)
			(stroke
				(width 0)
				(type default)
			)
			(fill yes)
			(layer "F.Fab")
		)
		(pad "1" smd rect
			(at -2.925064 -3.674872)
			(size 0.6096 1.3716)
			(layers "F.Cu" "F.Mask" "F.Paste")
			(net "PU_U181_INT")
		)
		(pad "2" smd rect
			(at -2.925064 -2.925064)
			(size 0.4064 1.3716)
			(layers "F.Cu" "F.Mask" "F.Paste")
			(net "TCA9539_0_ADD1")
		)
		(pad "3" smd rect
			(at -2.925064 -2.275078)
			(size 0.4064 1.3716)
			(layers "F.Cu" "F.Mask" "F.Paste")
			(net "PU_RST_SMB_U181_N")
		)
		(pad "4" smd rect
			(at -2.925064 -1.625092)
			(size 0.4064 1.3716)
			(layers "F.Cu" "F.Mask" "F.Paste")
			(net "RST_USB_HUB_N")
		)
		(pad "5" smd rect
			(at -2.925064 -0.975106)
			(size 0.4064 1.3716)
			(layers "F.Cu" "F.Mask" "F.Paste")
			(net "RST_SWB_BIC_N")
		)
		(pad "6" smd rect
			(at -2.925064 -0.32512)
			(size 0.4064 1.3716)
			(layers "F.Cu" "F.Mask" "F.Paste")
			(net "TP_TCA9539_0_P0_2")
		)
		(pad "7" smd rect
			(at -2.925064 0.32512)
			(size 0.4064 1.3716)
			(layers "F.Cu" "F.Mask" "F.Paste")
			(net "TP_TCA9539_0_P0_3")
		)
		(pad "8" smd rect
			(at -2.925064 0.975106)
			(size 0.4064 1.3716)
			(layers "F.Cu" "F.Mask" "F.Paste")
			(net "PRSNT_SWB_ISO_R1_N")
		)
		(pad "9" smd rect
			(at -2.925064 1.625092)
			(size 0.4064 1.3716)
			(layers "F.Cu" "F.Mask" "F.Paste")
			(net "GPU_PRSNT_N_ISO_R1")
		)
		(pad "10" smd rect
			(at -2.925064 2.275078)
			(size 0.4064 1.3716)
			(layers "F.Cu" "F.Mask" "F.Paste")
			(net "PRSNT_CABLE_GPU_B3_ISO_R1_N")
		)
		(pad "11" smd rect
			(at -2.925064 2.925064)
			(size 0.4064 1.3716)
			(layers "F.Cu" "F.Mask" "F.Paste")
			(net "PRSNT_CABLE_SWB_B2_ISO_R_N")
		)
		(pad "12" smd rect
			(at -2.925064 3.674872)
			(size 0.6096 1.3716)
			(layers "F.Cu" "F.Mask" "F.Paste")
			(net "GND")
		)
		(pad "13" smd rect
			(at 2.925064 3.674872)
			(size 0.6096 1.3716)
			(layers "F.Cu" "F.Mask" "F.Paste")
			(net "PRSNT_CABLE_GPU_A2_ISO_R1_N")
		)
		(pad "14" smd rect
			(at 2.925064 2.925064)
			(size 0.4064 1.3716)
			(layers "F.Cu" "F.Mask" "F.Paste")
			(net "PRSNT_CABLE_SWB_B1_ISO_R_N")
		)
		(pad "15" smd rect
			(at 2.925064 2.275078)
			(size 0.4064 1.3716)
			(layers "F.Cu" "F.Mask" "F.Paste")
			(net "GPU_BASE_ID0_R")
		)
		(pad "16" smd rect
			(at 2.925064 1.625092)
			(size 0.4064 1.3716)
			(layers "F.Cu" "F.Mask" "F.Paste")
			(net "GPU_BASE_ID1_R")
		)
		(pad "17" smd rect
			(at 2.925064 0.975106)
			(size 0.4064 1.3716)
			(layers "F.Cu" "F.Mask" "F.Paste")
			(net "GPU_PEX_STRAP0_R")
		)
		(pad "18" smd rect
			(at 2.925064 0.32512)
			(size 0.4064 1.3716)
			(layers "F.Cu" "F.Mask" "F.Paste")
			(net "GPU_PEX_STRAP1_R")
		)
		(pad "19" smd rect
			(at 2.925064 -0.32512)
			(size 0.4064 1.3716)
			(layers "F.Cu" "F.Mask" "F.Paste")
			(net "PRSNT_CABLE_GPU_A1_ISO_R1_N")
		)
		(pad "20" smd rect
			(at 2.925064 -0.975106)
			(size 0.4064 1.3716)
			(layers "F.Cu" "F.Mask" "F.Paste")
			(net "PRSNT_CABLE_GPU_A3_ISO_R_N")
		)
		(pad "21" smd rect
			(at 2.925064 -1.625092)
			(size 0.4064 1.3716)
			(layers "F.Cu" "F.Mask" "F.Paste")
			(net "TCA9539_0_ADD0")
		)
		(pad "22" smd rect
			(at 2.925064 -2.275078)
			(size 0.4064 1.3716)
			(layers "F.Cu" "F.Mask" "F.Paste")
			(net "SMB_IOEXP_3V3AUX_SCL_R1")
		)
		(pad "23" smd rect
			(at 2.925064 -2.925064)
			(size 0.4064 1.3716)
			(layers "F.Cu" "F.Mask" "F.Paste")
			(net "SMB_IOEXP_3V3AUX_SDA_R1")
		)
		(pad "24" smd rect
			(at 2.925064 -3.674872)
			(size 0.6096 1.3716)
			(layers "F.Cu" "F.Mask" "F.Paste")
			(net "P3V3_AUX")
		)
	)
)
